(kicad_pcb
	(version 20260206)
	(generator "pcbnew")
	(generator_version "10.0")
	(general
		(thickness 1.6)
		(legacy_teardrops no)
	)
	(paper "A4")
	(title_block
		(title "Wiwynn_Tioga_Pass_MB.brd")
		(comment 1 "Tioga Pass / footprints 3427-3433 of 4770")
	)
	(layers
		(0 "F.Cu" signal "TOP")
		(4 "In1.Cu" signal "L2GND")
		(6 "In2.Cu" signal "L3")
		(8 "In3.Cu" signal "L4GND")
		(10 "In4.Cu" signal "L5")
		(12 "In5.Cu" signal "L6GND")
		(14 "In6.Cu" signal "L7VCC")
		(16 "In7.Cu" signal "L8VCC")
		(18 "In8.Cu" signal "L9GND")
		(20 "In9.Cu" signal "L10")
		(22 "In10.Cu" signal "L11GND")
		(24 "In11.Cu" signal "L12")
		(26 "In12.Cu" signal "L13GND")
		(2 "B.Cu" signal "BOTTOM")
		(9 "F.Adhes" user "F.Adhesive")
		(11 "B.Adhes" user "B.Adhesive")
		(13 "F.Paste" user "Package Geometry/Pastemask Top")
		(15 "B.Paste" user "Package Geometry/Pastemask Bottom")
		(5 "F.SilkS" user "Ref Des/Silkscreen Top")
		(7 "B.SilkS" user "Ref Des/Silkscreen Bottom")
		(1 "F.Mask" user "Board Geometry/Soldermask Top")
		(3 "B.Mask" user "Board Geometry/Soldermask Bottom")
		(17 "Dwgs.User" user "User.Drawings")
		(19 "Cmts.User" user "User.Comments")
		(21 "Eco1.User" user "User.Eco1")
		(23 "Eco2.User" user "User.Eco2")
		(25 "Edge.Cuts" user "Board Geometry/Outline")
		(27 "Margin" user)
		(31 "F.CrtYd" user "Package Geometry/Place Bound Top")
		(29 "B.CrtYd" user "Package Geometry/Place Bound Bottom")
		(35 "F.Fab" user "Ref Des/Assembly Top")
		(33 "B.Fab" user "Ref Des/Assembly Bottom")
	)
	(footprint ""
		(layer "B.Cu")
		(at 330.984606 -65.303908 -90)
		(property "Reference" "R4P20"
			(at 0 0 90)
			(layer "B.SilkS")
			(hide yes)
			(effects
				(font
					(size 1.27 1.27)
				)
				(justify mirror)
			)
		)
		(property "Value" ""
			(at 0 0 90)
			(layer "B.Fab")
			(effects
				(font
					(size 1.27 1.27)
				)
				(justify mirror)
			)
		)
		(duplicate_pad_numbers_are_jumpers no)
		(fp_poly
			(pts
				(xy 0.2794 -0.1016) (xy -0.2794 -0.1016) (xy -0.2794 0.9906) (xy 0.2794 0.9906)
			)
			(stroke
				(width 0)
				(type default)
			)
			(fill no)
			(layer "B.CrtYd")
		)
		(fp_line
			(start -0.2794 0.9906)
			(end -0.2794 -0.1016)
			(stroke
				(width 0.1)
				(type default)
			)
			(layer "B.Fab")
		)
		(fp_line
			(start 0.2794 0.9906)
			(end -0.2794 0.9906)
			(stroke
				(width 0.1)
				(type default)
			)
			(layer "B.Fab")
		)
		(fp_line
			(start -0.2794 -0.1016)
			(end 0.2794 -0.1016)
			(stroke
				(width 0.1)
				(type default)
			)
			(layer "B.Fab")
		)
		(fp_line
			(start 0.2794 -0.1016)
			(end 0.2794 0.9906)
			(stroke
				(width 0.1)
				(type default)
			)
			(layer "B.Fab")
		)
		(pad "1" smd rect
			(at 0 0 90)
			(size 0.508 0.508)
			(layers "B.Cu" "B.Mask" "B.Paste")
			(net "H_CPU0_MEMDEF_MEMHOT_G_N")
		)
		(pad "2" smd rect
			(at 0 0.889 90)
			(size 0.508 0.508)
			(layers "B.Cu" "B.Mask" "B.Paste")
			(net "PVCCIO_CPU0")
		)
		(zone
			(layer "B.Cu")
			(hatch none 0.5)
			(connect_pads
				(clearance 0)
			)
			(min_thickness 0.25)
			(keepout
				(tracks not_allowed)
				(vias allowed)
				(pads allowed)
				(copperpour not_allowed)
				(footprints allowed)
			)
			(placement
				(enabled no)
				(sheetname "")
			)
			(fill
				(thermal_gap 0.5)
				(thermal_bridge_width 0.5)
				(island_removal_mode 0)
			)
			(polygon
				(pts
					(xy 330.349606 -65.049908) (xy 330.349606 -65.557908) (xy 330.730606 -65.557908) (xy 330.730606 -65.049908)
				)
			)
		)
		(zone
			(layer "B.Cu")
			(hatch none 0.5)
			(connect_pads
				(clearance 0)
			)
			(min_thickness 0.25)
			(keepout
				(tracks allowed)
				(vias not_allowed)
				(pads allowed)
				(copperpour not_allowed)
				(footprints allowed)
			)
			(placement
				(enabled no)
				(sheetname "")
			)
			(fill
				(thermal_gap 0.5)
				(thermal_bridge_width 0.5)
				(island_removal_mode 0)
			)
			(polygon
				(pts
					(xy 330.730606 -65.049908) (xy 330.730606 -65.557908) (xy 330.349606 -65.557908) (xy 330.349606 -65.049908)
				)
			)
		)
	)
	(footprint ""
		(layer "B.Cu")
		(at 162.91306 -85.598 90)
		(property "Reference" "R7P1"
			(at 0 0 90)
			(layer "B.SilkS")
			(hide yes)
			(effects
				(font
					(size 1.27 1.27)
				)
				(justify mirror)
			)
		)
		(property "Value" ""
			(at 0 0 90)
			(layer "B.Fab")
			(effects
				(font
					(size 1.27 1.27)
				)
				(justify mirror)
			)
		)
		(duplicate_pad_numbers_are_jumpers no)
		(fp_poly
			(pts
				(xy 0.2794 -0.1016) (xy -0.2794 -0.1016) (xy -0.2794 0.9906) (xy 0.2794 0.9906)
			)
			(stroke
				(width 0)
				(type default)
			)
			(fill no)
			(layer "B.CrtYd")
		)
		(fp_line
			(start 0.2794 -0.1016)
			(end 0.2794 0.9906)
			(stroke
				(width 0.1)
				(type default)
			)
			(layer "B.Fab")
		)
		(fp_line
			(start -0.2794 -0.1016)
			(end 0.2794 -0.1016)
			(stroke
				(width 0.1)
				(type default)
			)
			(layer "B.Fab")
		)
		(fp_line
			(start 0.2794 0.9906)
			(end -0.2794 0.9906)
			(stroke
				(width 0.1)
				(type default)
			)
			(layer "B.Fab")
		)
		(fp_line
			(start -0.2794 0.9906)
			(end -0.2794 -0.1016)
			(stroke
				(width 0.1)
				(type default)
			)
			(layer "B.Fab")
		)
		(pad "1" smd rect
			(at 0 0 270)
			(size 0.508 0.508)
			(layers "B.Cu" "B.Mask" "B.Paste")
			(net "CLK_100M_CPU1_BCLK2_DP")
		)
		(pad "2" smd rect
			(at 0 0.889 270)
			(size 0.508 0.508)
			(layers "B.Cu" "B.Mask" "B.Paste")
			(net "GND")
		)
		(zone
			(layer "B.Cu")
			(hatch none 0.5)
			(connect_pads
				(clearance 0)
			)
			(min_thickness 0.25)
			(keepout
				(tracks allowed)
				(vias not_allowed)
				(pads allowed)
				(copperpour not_allowed)
				(footprints allowed)
			)
			(placement
				(enabled no)
				(sheetname "")
			)
			(fill
				(thermal_gap 0.5)
				(thermal_bridge_width 0.5)
				(island_removal_mode 0)
			)
			(polygon
				(pts
					(xy 163.16706 -85.852) (xy 163.16706 -85.344) (xy 163.54806 -85.344) (xy 163.54806 -85.852)
				)
			)
		)
		(zone
			(layer "B.Cu")
			(hatch none 0.5)
			(connect_pads
				(clearance 0)
			)
			(min_thickness 0.25)
			(keepout
				(tracks not_allowed)
				(vias allowed)
				(pads allowed)
				(copperpour not_allowed)
				(footprints allowed)
			)
			(placement
				(enabled no)
				(sheetname "")
			)
			(fill
				(thermal_gap 0.5)
				(thermal_bridge_width 0.5)
				(island_removal_mode 0)
			)
			(polygon
				(pts
					(xy 163.54806 -85.852) (xy 163.54806 -85.344) (xy 163.16706 -85.344) (xy 163.16706 -85.852)
				)
			)
		)
	)
	(footprint ""
		(layer "B.Cu")
		(at 404.0251 -29.337 90)
		(property "Reference" "R25W110"
			(at 0.8382 -0.67818 90)
			(unlocked yes)
			(layer "B.SilkS")
			(effects
				(font
					(size 0.4064 0.254)
					(thickness 0.1524)
				)
				(justify left mirror)
			)
		)
		(property "Value" ""
			(at 0 0 90)
			(layer "B.Fab")
			(effects
				(font
					(size 1.27 1.27)
				)
				(justify mirror)
			)
		)
		(duplicate_pad_numbers_are_jumpers no)
		(fp_poly
			(pts
				(xy 0.2794 -0.1016) (xy -0.2794 -0.1016) (xy -0.2794 0.9906) (xy 0.2794 0.9906)
			)
			(stroke
				(width 0)
				(type default)
			)
			(fill no)
			(layer "B.CrtYd")
		)
		(fp_line
			(start 0.2794 -0.1016)
			(end 0.2794 0.9906)
			(stroke
				(width 0.1)
				(type default)
			)
			(layer "B.Fab")
		)
		(fp_line
			(start -0.2794 -0.1016)
			(end 0.2794 -0.1016)
			(stroke
				(width 0.1)
				(type default)
			)
			(layer "B.Fab")
		)
		(fp_line
			(start 0.2794 0.9906)
			(end -0.2794 0.9906)
			(stroke
				(width 0.1)
				(type default)
			)
			(layer "B.Fab")
		)
		(fp_line
			(start -0.2794 0.9906)
			(end -0.2794 -0.1016)
			(stroke
				(width 0.1)
				(type default)
			)
			(layer "B.Fab")
		)
		(pad "1" smd rect
			(at 0 0 270)
			(size 0.508 0.508)
			(layers "B.Cu" "B.Mask" "B.Paste")
			(net "P3V3_STBY")
		)
		(pad "2" smd rect
			(at 0 0.889 270)
			(size 0.508 0.508)
			(layers "B.Cu" "B.Mask" "B.Paste")
			(net "TP_RGMII2TXD2_GPIOU2")
		)
		(zone
			(layer "B.Cu")
			(hatch none 0.5)
			(connect_pads
				(clearance 0)
			)
			(min_thickness 0.25)
			(keepout
				(tracks allowed)
				(vias not_allowed)
				(pads allowed)
				(copperpour not_allowed)
				(footprints allowed)
			)
			(placement
				(enabled no)
				(sheetname "")
			)
			(fill
				(thermal_gap 0.5)
				(thermal_bridge_width 0.5)
				(island_removal_mode 0)
			)
			(polygon
				(pts
					(xy 404.2791 -29.591) (xy 404.2791 -29.083) (xy 404.6601 -29.083) (xy 404.6601 -29.591)
				)
			)
		)
		(zone
			(layer "B.Cu")
			(hatch none 0.5)
			(connect_pads
				(clearance 0)
			)
			(min_thickness 0.25)
			(keepout
				(tracks not_allowed)
				(vias allowed)
				(pads allowed)
				(copperpour not_allowed)
				(footprints allowed)
			)
			(placement
				(enabled no)
				(sheetname "")
			)
			(fill
				(thermal_gap 0.5)
				(thermal_bridge_width 0.5)
				(island_removal_mode 0)
			)
			(polygon
				(pts
					(xy 404.6601 -29.591) (xy 404.6601 -29.083) (xy 404.2791 -29.083) (xy 404.2791 -29.591)
				)
			)
		)
	)
	(footprint ""
		(layer "B.Cu")
		(at 276.381464 -135.4074 90)
		(property "Reference" "C4M2"
			(at -1.848866 0.752348 90)
			(unlocked yes)
			(layer "B.SilkS")
			(effects
				(font
					(size 1.27 0.9652)
					(thickness 0.1524)
				)
				(justify mirror)
			)
		)
		(property "Value" ""
			(at 0 0 90)
			(layer "B.Fab")
			(effects
				(font
					(size 1.27 1.27)
				)
				(justify mirror)
			)
		)
		(duplicate_pad_numbers_are_jumpers no)
		(fp_rect
			(start 0.500126 1.598422)
			(end -0.500126 -0.201422)
			(stroke
				(width 0)
				(type default)
			)
			(fill no)
			(layer "B.CrtYd")
		)
		(fp_line
			(start 0.500126 -0.201422)
			(end -0.500126 -0.201422)
			(stroke
				(width 0.1)
				(type default)
			)
			(layer "B.Fab")
		)
		(fp_line
			(start -0.500126 -0.201422)
			(end -0.500126 1.598422)
			(stroke
				(width 0.1)
				(type default)
			)
			(layer "B.Fab")
		)
		(fp_line
			(start 0.500126 1.598422)
			(end 0.500126 -0.201422)
			(stroke
				(width 0.1)
				(type default)
			)
			(layer "B.Fab")
		)
		(fp_line
			(start -0.500126 1.598422)
			(end 0.500126 1.598422)
			(stroke
				(width 0.1)
				(type default)
			)
			(layer "B.Fab")
		)
		(pad "1" smd rect
			(at 0 0)
			(size 0.889 0.9906)
			(layers "B.Cu" "B.Mask" "B.Paste")
			(net "PVDDQ_DEF")
		)
		(pad "2" smd rect
			(at 0 1.397)
			(size 0.889 0.9906)
			(layers "B.Cu" "B.Mask" "B.Paste")
			(net "GND")
		)
		(zone
			(layer "B.Cu")
			(hatch none 0.5)
			(connect_pads
				(clearance 0)
			)
			(min_thickness 0.25)
			(keepout
				(tracks allowed)
				(vias not_allowed)
				(pads allowed)
				(copperpour not_allowed)
				(footprints allowed)
			)
			(placement
				(enabled no)
				(sheetname "")
			)
			(fill
				(thermal_gap 0.5)
				(thermal_bridge_width 0.5)
				(island_removal_mode 0)
			)
			(polygon
				(pts
					(xy 277.333964 -135.9027) (xy 276.825964 -135.9027) (xy 276.825964 -134.9121) (xy 277.333964 -134.9121)
				)
			)
		)
		(zone
			(layer "B.Cu")
			(hatch none 0.5)
			(connect_pads
				(clearance 0)
			)
			(min_thickness 0.25)
			(keepout
				(tracks not_allowed)
				(vias allowed)
				(pads allowed)
				(copperpour not_allowed)
				(footprints allowed)
			)
			(placement
				(enabled no)
				(sheetname "")
			)
			(fill
				(thermal_gap 0.5)
				(thermal_bridge_width 0.5)
				(island_removal_mode 0)
			)
			(polygon
				(pts
					(xy 277.333964 -135.9027) (xy 276.825964 -135.9027) (xy 276.825964 -134.9121) (xy 277.333964 -134.9121)
				)
			)
		)
	)
	(footprint ""
		(layer "B.Cu")
		(at 350.9772 -84.328 90)
		(property "Reference" "C3P3"
			(at 0 0 90)
			(layer "B.SilkS")
			(hide yes)
			(effects
				(font
					(size 1.27 1.27)
				)
				(justify mirror)
			)
		)
		(property "Value" ""
			(at 0 0 90)
			(layer "B.Fab")
			(effects
				(font
					(size 1.27 1.27)
				)
				(justify mirror)
			)
		)
		(duplicate_pad_numbers_are_jumpers no)
		(fp_poly
			(pts
				(xy -0.3048 -0.1016) (xy -0.3048 0.9906) (xy 0.3048 0.9906) (xy 0.3048 -0.1016)
			)
			(stroke
				(width 0)
				(type default)
			)
			(fill no)
			(layer "B.CrtYd")
		)
		(fp_line
			(start 0.3048 -0.1016)
			(end 0.3048 0.9906)
			(stroke
				(width 0.1)
				(type default)
			)
			(layer "B.Fab")
		)
		(fp_line
			(start -0.3048 -0.1016)
			(end 0.3048 -0.1016)
			(stroke
				(width 0.1)
				(type default)
			)
			(layer "B.Fab")
		)
		(fp_line
			(start 0.3048 0.9906)
			(end -0.3048 0.9906)
			(stroke
				(width 0.1)
				(type default)
			)
			(layer "B.Fab")
		)
		(fp_line
			(start -0.3048 0.9906)
			(end -0.3048 -0.1016)
			(stroke
				(width 0.1)
				(type default)
			)
			(layer "B.Fab")
		)
		(pad "1" smd rect
			(at 0 0 270)
			(size 0.508 0.508)
			(layers "B.Cu" "B.Mask" "B.Paste")
			(net "VR_PVCCIO_CPU0_VDD")
		)
		(pad "2" smd rect
			(at 0 0.889 270)
			(size 0.508 0.508)
			(layers "B.Cu" "B.Mask" "B.Paste")
			(net "GND")
		)
		(zone
			(layer "B.Cu")
			(hatch none 0.5)
			(connect_pads
				(clearance 0)
			)
			(min_thickness 0.25)
			(keepout
				(tracks allowed)
				(vias not_allowed)
				(pads allowed)
				(copperpour not_allowed)
				(footprints allowed)
			)
			(placement
				(enabled no)
				(sheetname "")
			)
			(fill
				(thermal_gap 0.5)
				(thermal_bridge_width 0.5)
				(island_removal_mode 0)
			)
			(polygon
				(pts
					(xy 351.2312 -84.582) (xy 351.2312 -84.074) (xy 351.6122 -84.074) (xy 351.6122 -84.582)
				)
			)
		)
		(zone
			(layer "B.Cu")
			(hatch none 0.5)
			(connect_pads
				(clearance 0)
			)
			(min_thickness 0.25)
			(keepout
				(tracks not_allowed)
				(vias allowed)
				(pads allowed)
				(copperpour not_allowed)
				(footprints allowed)
			)
			(placement
				(enabled no)
				(sheetname "")
			)
			(fill
				(thermal_gap 0.5)
				(thermal_bridge_width 0.5)
				(island_removal_mode 0)
			)
			(polygon
				(pts
					(xy 351.6122 -84.582) (xy 351.6122 -84.074) (xy 351.2312 -84.074) (xy 351.2312 -84.582)
				)
			)
		)
	)
	(footprint ""
		(layer "B.Cu")
		(at 415.442146 -39.735252 90)
		(property "Reference" "C25W47"
			(at -0.97536 0.76708 180)
			(unlocked yes)
			(layer "B.SilkS")
			(effects
				(font
					(size 0.4064 0.254)
					(thickness 0.1524)
				)
				(justify mirror)
			)
		)
		(property "Value" ""
			(at 0 0 90)
			(layer "B.Fab")
			(effects
				(font
					(size 1.27 1.27)
				)
				(justify mirror)
			)
		)
		(duplicate_pad_numbers_are_jumpers no)
		(fp_poly
			(pts
				(xy 0.4953 -0.2032) (xy -0.4953 -0.2032) (xy -0.4953 1.6002) (xy 0.4953 1.6002)
			)
			(stroke
				(width 0)
				(type default)
			)
			(fill no)
			(layer "B.CrtYd")
		)
		(fp_line
			(start 0.4953 -0.2032)
			(end -0.4953 -0.2032)
			(stroke
				(width 0.1)
				(type default)
			)
			(layer "B.Fab")
		)
		(fp_line
			(start -0.4953 -0.2032)
			(end -0.4953 1.6002)
			(stroke
				(width 0.1)
				(type default)
			)
			(layer "B.Fab")
		)
		(fp_line
			(start 0.4953 1.6002)
			(end 0.4953 -0.2032)
			(stroke
				(width 0.1)
				(type default)
			)
			(layer "B.Fab")
		)
		(fp_line
			(start -0.4953 1.6002)
			(end 0.4953 1.6002)
			(stroke
				(width 0.1)
				(type default)
			)
			(layer "B.Fab")
		)
		(pad "1" smd rect
			(at 0 0 270)
			(size 0.762 0.889)
			(layers "B.Cu" "B.Mask" "B.Paste")
			(net "VCC_D_3V3")
		)
		(pad "2" smd rect
			(at 0 1.397 270)
			(size 0.762 0.889)
			(layers "B.Cu" "B.Mask" "B.Paste")
			(net "GND")
		)
		(zone
			(layer "B.Cu")
			(hatch none 0.5)
			(connect_pads
				(clearance 0)
			)
			(min_thickness 0.25)
			(keepout
				(tracks not_allowed)
				(vias allowed)
				(pads allowed)
				(copperpour not_allowed)
				(footprints allowed)
			)
			(placement
				(enabled no)
				(sheetname "")
			)
			(fill
				(thermal_gap 0.5)
				(thermal_bridge_width 0.5)
				(island_removal_mode 0)
			)
			(polygon
				(pts
					(xy 415.886646 -40.116252) (xy 415.886646 -39.354252) (xy 416.394646 -39.354252) (xy 416.394646 -40.116252)
				)
			)
		)
	)
	(footprint ""
		(layer "B.Cu")
		(at 210.847432 -62.611 -90)
		(property "Reference" "C6R3"
			(at -2.64033 -3.528568 0)
			(unlocked yes)
			(layer "B.SilkS")
			(effects
				(font
					(size 0.7874 0.5842)
					(thickness 0.1524)
				)
				(justify mirror)
			)
		)
		(property "Value" ""
			(at 0 0 90)
			(layer "B.Fab")
			(effects
				(font
					(size 1.27 1.27)
				)
				(justify mirror)
			)
		)
		(duplicate_pad_numbers_are_jumpers no)
		(fp_line
			(start -2.286 7.366)
			(end -1.600708 7.366)
			(stroke
				(width 0.1524)
				(type default)
			)
			(layer "B.SilkS")
		)
		(fp_line
			(start -2.286 7.366)
			(end -2.286 1.63195)
			(stroke
				(width 0.1524)
				(type default)
			)
			(layer "B.SilkS")
		)
		(fp_line
			(start 2.286 7.366)
			(end 1.60147 7.366)
			(stroke
				(width 0.1524)
				(type default)
			)
			(layer "B.SilkS")
		)
		(fp_line
			(start 2.286 7.366)
			(end 2.286 1.632712)
			(stroke
				(width 0.1524)
				(type default)
			)
			(layer "B.SilkS")
		)
		(fp_line
			(start -2.504948 1.633728)
			(end -1.6002 1.633728)
			(stroke
				(width 0.1524)
				(type default)
			)
			(layer "B.SilkS")
		)
		(fp_line
			(start 2.563114 1.633728)
			(end 1.6002 1.633728)
			(stroke
				(width 0.1524)
				(type default)
			)
			(layer "B.SilkS")
		)
		(fp_line
			(start -2.504948 -1.616456)
			(end -2.504948 1.633728)
			(stroke
				(width 0.1524)
				(type default)
			)
			(layer "B.SilkS")
		)
		(fp_line
			(start -1.6002 -1.616456)
			(end -2.504948 -1.616456)
			(stroke
				(width 0.1524)
				(type default)
			)
			(layer "B.SilkS")
		)
		(fp_line
			(start 1.6002 -1.616456)
			(end 2.563114 -1.616456)
			(stroke
				(width 0.1524)
				(type default)
			)
			(layer "B.SilkS")
		)
		(fp_line
			(start 2.563114 -1.616456)
			(end 2.563114 1.633728)
			(stroke
				(width 0.1524)
				(type default)
			)
			(layer "B.SilkS")
		)
		(fp_rect
			(start 2.286 7.366)
			(end -2.286 -0.254)
			(stroke
				(width 0)
				(type default)
			)
			(fill no)
			(layer "B.CrtYd")
		)
		(fp_line
			(start -2.286 7.366)
			(end 2.286 7.366)
			(stroke
				(width 0.1)
				(type default)
			)
			(layer "B.Fab")
		)
		(fp_line
			(start 2.286 7.366)
			(end 2.286 -0.254)
			(stroke
				(width 0.1)
				(type default)
			)
			(layer "B.Fab")
		)
		(fp_line
			(start -2.286 -0.254)
			(end -2.286 7.366)
			(stroke
				(width 0.1)
				(type default)
			)
			(layer "B.Fab")
		)
		(fp_line
			(start 2.286 -0.254)
			(end -2.286 -0.254)
			(stroke
				(width 0.1)
				(type default)
			)
			(layer "B.Fab")
		)
		(pad "1" smd rect
			(at 0 0 90)
			(size 2.54 3.048)
			(layers "B.Cu" "B.Mask" "B.Paste")
			(net "PVCCIN_CPU0")
		)
		(pad "2" smd rect
			(at 0 7.112 90)
			(size 2.54 3.048)
			(layers "B.Cu" "B.Mask" "B.Paste")
			(net "GND")
		)
	)
)
